# S9S_MB_2U (Grand Teton) — schematic netlist excerpt (pin names and nets, part order shuffled) for the footprints in the layout excerpt that follows; sources: Cadence DE-HDL packaged netlist, KiCad conversion of 03242023_DA0F0TMBIJ0_F0T_Motherboard_J_brd_V01_OCP.brd

PC1240  Q_CAP  22UF 4V 20% X6S  pkg C0805  page 263 : A = P1V8_PCH_AUX ; B = GND
R816  Q_RES  0 5% CHIP  pkg 0402LF  page 130 : A = RST_PLD_CPU1_DRAM_AB_N ; B = RST_M_AB_CPU1_FPGA_N
PC544_P1_3  Q_CAP  22UF 4V 20% X6S  pkg C0805  page 286 : A = PVCCIN_CPU1 ; B = GND

(kicad_pcb
	(version 20260206)
	(generator "pcbnew")
	(generator_version "10.0")
	(general
		(thickness 1.6)
		(legacy_teardrops no)
	)
	(paper "A4")
	(title_block
		(title "03242023_DA0F0TMBIJ0_F0T_Motherboard_J_brd_V01_OCP.brd")
		(comment 1 "Grand Teton / footprints 4260-4262 of 6105")
	)
	(layers
		(0 "F.Cu" signal "TOP")
		(4 "In1.Cu" signal "GND")
		(6 "In2.Cu" signal "IN1")
		(8 "In3.Cu" signal "GND1")
		(10 "In4.Cu" signal "IN2")
		(12 "In5.Cu" signal "GND2")
		(14 "In6.Cu" signal "IN3")
		(16 "In7.Cu" signal "GND3")
		(18 "In8.Cu" signal "VCC")
		(20 "In9.Cu" signal "VCC1")
		(22 "In10.Cu" signal "GND4")
		(24 "In11.Cu" signal "IN4")
		(26 "In12.Cu" signal "GND5")
		(28 "In13.Cu" signal "IN5")
		(30 "In14.Cu" signal "GND6")
		(32 "In15.Cu" signal "IN6")
		(34 "In16.Cu" signal "GND7")
		(2 "B.Cu" signal "BOTTOM")
		(9 "F.Adhes" user "F.Adhesive")
		(11 "B.Adhes" user "B.Adhesive")
		(13 "F.Paste" user "Package Geometry/Pastemask Top")
		(15 "B.Paste" user "Package Geometry/Pastemask Bottom")
		(5 "F.SilkS" user "Ref Des/Silkscreen Top")
		(7 "B.SilkS" user "Ref Des/Silkscreen Bottom")
		(1 "F.Mask" user "Board Geometry/Soldermask Top")
		(3 "B.Mask" user "Board Geometry/Soldermask Bottom")
		(17 "Dwgs.User" user "User.Drawings")
		(19 "Cmts.User" user "User.Comments")
		(21 "Eco1.User" user "User.Eco1")
		(23 "Eco2.User" user "User.Eco2")
		(25 "Edge.Cuts" user "Board Geometry/Outline")
		(27 "Margin" user)
		(31 "F.CrtYd" user "Package Geometry/Place Bound Top")
		(29 "B.CrtYd" user "Package Geometry/Place Bound Bottom")
		(35 "F.Fab" user "Ref Des/Assembly Top")
		(33 "B.Fab" user "Ref Des/Assembly Bottom")
	)
	(footprint ""
		(layer "B.Cu")
		(at 36.583366 -192.924176 -90)
		(property "Reference" "R816"
			(at 0 0 90)
			(layer "B.SilkS")
			(hide yes)
			(effects
				(font
					(size 1.27 1.27)
				)
				(justify mirror)
			)
		)
		(property "Value" ""
			(at 0 0 90)
			(layer "B.Fab")
			(effects
				(font
					(size 1.27 1.27)
				)
				(justify mirror)
			)
		)
		(duplicate_pad_numbers_are_jumpers no)
		(fp_line
			(start -0.7874 0.4064)
			(end 0.7874 0.4064)
			(stroke
				(width 0.1524)
				(type default)
			)
			(layer "B.SilkS")
		)
		(fp_line
			(start 0.7874 0.4064)
			(end 0.7874 -0.4064)
			(stroke
				(width 0.1524)
				(type default)
			)
			(layer "B.SilkS")
		)
		(fp_line
			(start -0.7874 -0.4064)
			(end -0.7874 0.4064)
			(stroke
				(width 0.1524)
				(type default)
			)
			(layer "B.SilkS")
		)
		(fp_line
			(start 0.7874 -0.4064)
			(end -0.7874 -0.4064)
			(stroke
				(width 0.1524)
				(type default)
			)
			(layer "B.SilkS")
		)
		(fp_line
			(start -0.67945 0.3048)
			(end -0.120396 0.3048)
			(stroke
				(width 0.1)
				(type default)
			)
			(layer "B.Fab")
		)
		(fp_line
			(start -0.120396 0.3048)
			(end -0.120396 0.2794)
			(stroke
				(width 0.1)
				(type default)
			)
			(layer "B.Fab")
		)
		(fp_line
			(start 0.12065 0.3048)
			(end 0.67945 0.3048)
			(stroke
				(width 0.1)
				(type default)
			)
			(layer "B.Fab")
		)
		(fp_line
			(start 0.67945 0.3048)
			(end 0.67945 -0.305054)
			(stroke
				(width 0.1)
				(type default)
			)
			(layer "B.Fab")
		)
		(fp_line
			(start -0.120396 0.2794)
			(end 0.12065 0.2794)
			(stroke
				(width 0.1)
				(type default)
			)
			(layer "B.Fab")
		)
		(fp_line
			(start 0.12065 0.2794)
			(end 0.12065 0.3048)
			(stroke
				(width 0.1)
				(type default)
			)
			(layer "B.Fab")
		)
		(fp_line
			(start -0.12065 -0.2794)
			(end -0.12065 -0.3048)
			(stroke
				(width 0.1)
				(type default)
			)
			(layer "B.Fab")
		)
		(fp_line
			(start 0.12065 -0.2794)
			(end -0.12065 -0.2794)
			(stroke
				(width 0.1)
				(type default)
			)
			(layer "B.Fab")
		)
		(fp_line
			(start -0.67945 -0.3048)
			(end -0.67945 0.3048)
			(stroke
				(width 0.1)
				(type default)
			)
			(layer "B.Fab")
		)
		(fp_line
			(start -0.12065 -0.3048)
			(end -0.67945 -0.3048)
			(stroke
				(width 0.1)
				(type default)
			)
			(layer "B.Fab")
		)
		(fp_line
			(start 0.12065 -0.305054)
			(end 0.12065 -0.2794)
			(stroke
				(width 0.1)
				(type default)
			)
			(layer "B.Fab")
		)
		(fp_line
			(start 0.67945 -0.305054)
			(end 0.12065 -0.305054)
			(stroke
				(width 0.1)
				(type default)
			)
			(layer "B.Fab")
		)
		(pad "1" smd circle
			(at 0.40005 0 90)
			(size 0 0)
			(layers "B.Cu" "B.Mask" "B.Paste")
			(net "RST_PLD_CPU1_DRAM_AB_N")
		)
		(pad "2" smd circle
			(at -0.40005 0 90)
			(size 0 0)
			(layers "B.Cu" "B.Mask" "B.Paste")
			(net "RST_M_AB_CPU1_FPGA_N")
		)
	)
	(footprint ""
		(layer "B.Cu")
		(at 376.468132 -74.614024 180)
		(property "Reference" "PC1240"
			(at 0 0 0)
			(layer "B.SilkS")
			(hide yes)
			(effects
				(font
					(size 1.27 1.27)
				)
				(justify mirror)
			)
		)
		(property "Value" ""
			(at 0 0 0)
			(layer "B.Fab")
			(effects
				(font
					(size 1.27 1.27)
				)
				(justify mirror)
			)
		)
		(duplicate_pad_numbers_are_jumpers no)
		(fp_line
			(start 1.524 0.762)
			(end 1.524 -0.762)
			(stroke
				(width 0.1524)
				(type default)
			)
			(layer "B.SilkS")
		)
		(fp_line
			(start 1.524 -0.762)
			(end -1.524 -0.762)
			(stroke
				(width 0.1524)
				(type default)
			)
			(layer "B.SilkS")
		)
		(fp_line
			(start -1.524 0.762)
			(end 1.524 0.762)
			(stroke
				(width 0.1524)
				(type default)
			)
			(layer "B.SilkS")
		)
		(fp_line
			(start -1.524 -0.762)
			(end -1.524 0.762)
			(stroke
				(width 0.1524)
				(type default)
			)
			(layer "B.SilkS")
		)
		(fp_line
			(start 1.1049 0.724916)
			(end -1.1049 0.724916)
			(stroke
				(width 0.1)
				(type default)
			)
			(layer "B.Fab")
		)
		(fp_line
			(start 1.1049 -0.724916)
			(end 1.1049 0.724916)
			(stroke
				(width 0.1)
				(type default)
			)
			(layer "B.Fab")
		)
		(fp_line
			(start -1.1049 0.724916)
			(end -1.1049 -0.724916)
			(stroke
				(width 0.1)
				(type default)
			)
			(layer "B.Fab")
		)
		(fp_line
			(start -1.1049 -0.724916)
			(end 1.1049 -0.724916)
			(stroke
				(width 0.1)
				(type default)
			)
			(layer "B.Fab")
		)
		(pad "1" smd rect
			(at 0.889 0 180)
			(size 1.016 1.27)
			(layers "B.Cu" "B.Mask" "B.Paste")
			(net "P1V8_PCH_AUX")
		)
		(pad "2" smd rect
			(at -0.889 0 180)
			(size 1.016 1.27)
			(layers "B.Cu" "B.Mask" "B.Paste")
			(net "GND")
		)
	)
	(footprint ""
		(layer "B.Cu")
		(at 110.051596 -324.792086 -90)
		(property "Reference" "PC544_P1_3"
			(at 0 0 90)
			(layer "B.SilkS")
			(hide yes)
			(effects
				(font
					(size 1.27 1.27)
				)
				(justify mirror)
			)
		)
		(property "Value" ""
			(at 0 0 90)
			(layer "B.Fab")
			(effects
				(font
					(size 1.27 1.27)
				)
				(justify mirror)
			)
		)
		(duplicate_pad_numbers_are_jumpers no)
		(fp_line
			(start -1.524 0.762)
			(end 1.524 0.762)
			(stroke
				(width 0.1524)
				(type default)
			)
			(layer "B.SilkS")
		)
		(fp_line
			(start 1.524 0.762)
			(end 1.524 -0.762)
			(stroke
				(width 0.1524)
				(type default)
			)
			(layer "B.SilkS")
		)
		(fp_line
			(start -1.524 -0.762)
			(end -1.524 0.762)
			(stroke
				(width 0.1524)
				(type default)
			)
			(layer "B.SilkS")
		)
		(fp_line
			(start 1.524 -0.762)
			(end -1.524 -0.762)
			(stroke
				(width 0.1524)
				(type default)
			)
			(layer "B.SilkS")
		)
		(fp_line
			(start -1.1049 0.724916)
			(end -1.1049 -0.724916)
			(stroke
				(width 0.1)
				(type default)
			)
			(layer "B.Fab")
		)
		(fp_line
			(start 1.1049 0.724916)
			(end -1.1049 0.724916)
			(stroke
				(width 0.1)
				(type default)
			)
			(layer "B.Fab")
		)
		(fp_line
			(start -1.1049 -0.724916)
			(end 1.1049 -0.724916)
			(stroke
				(width 0.1)
				(type default)
			)
			(layer "B.Fab")
		)
		(fp_line
			(start 1.1049 -0.724916)
			(end 1.1049 0.724916)
			(stroke
				(width 0.1)
				(type default)
			)
			(layer "B.Fab")
		)
		(pad "1" smd rect
			(at 0.889 0 270)
			(size 1.016 1.27)
			(layers "B.Cu" "B.Mask" "B.Paste")
			(net "PVCCIN_CPU1")
		)
		(pad "2" smd rect
			(at -0.889 0 270)
			(size 1.016 1.27)
			(layers "B.Cu" "B.Mask" "B.Paste")
			(net "GND")
		)
	)
)
